# Lightning_M.2_Pick & place.xlsx — Sheet1 (pick-and-place)
| 15750-1.1229WZS1359.brd |  |  |  |  |  |  |  |  |
| Date  Tue Mar 07 17:38:38 2017 |  |  |  |  |  |  |  |  |
| Total Components:  157 |  |  |  |  |  |  |  |  |
| Component Report |  |  |  |  |  |  |  |  |
| REFDES | COMP_DEVICE_TYPE | COMP_VALUE | COMP_TOL | COMP_PACKAGE | SYM_X | SYM_Y | SYM_ROTATE | SYM_MIRROR |
| C1 | C402H22 | SC1U6D3V2KX-9-GP | 078.10520.02F1 | C402H22 | 2355 | 1755 | 270 | NO |
| C2 | C402H22 | SCD1U16V2KX-3GP | 78.10421.2FL | C402H22 | 2355 | 1835 | 270 | NO |
| C3 | C402H22 | SCD1U16V2KX-3GP | 78.10421.2FL | C402H22 | 2355 | 1795 | 270 | NO |
| C7 | C402H22 | SCD1U16V2KX-3GP | 78.10421.2FL | C402H22 | 1005 | 3406.89 | 0 | NO |
| C8 | C402H22 | SCD1U16V2KX-3GP | 78.10421.2FL | C402H22 | 1020 | 3100 | 90 | NO |
| C9 | C402H22 | SCD1U16V2KX-3GP | 78.10421.2FL | C402H22 | 1095 | 2850 | 0 | NO |
| C10 | C402H22 | SCD1U16V2KX-3GP | 78.10421.2FL | C402H22 | 1030 | 2825 | 0 | NO |
| C11 | C402H22 | SCD1U16V2KX-3GP | 78.10421.2FL | C402H22 | 1300 | 2935 | 0 | NO |
| C12 | C402H22 | SC1U6D3V2KX-9-GP | 078.10520.02F1 | C402H22 | 2490 | 2545 | 180 | NO |
| C13 | C402H22 | SCD1U16V2KX-3GP | 78.10421.2FL | C402H22 | 2355 | 2470 | 270 | NO |
| C14 | C402H22 | SCD1U16V2KX-3GP | 78.10421.2FL | C402H22 | 2355 | 2430 | 270 | NO |
| C15 | C402H22 | SCD1U16V2KX-3GP | 78.10421.2FL | C402H22 | 2355 | 2385 | 270 | NO |
| C16 | C805H58 | SC10U6D3V5KX-4GP | 78.10620.21L | C805H58 | 2385 | 2470 | 270 | YES |
| C17 | C805H58 | SC10U6D3V5KX-4GP | 78.10620.21L | C805H58 | 2385 | 1795 | 270 | YES |
| C18 | C402H22 | SC1U6D3V2KX-9-GP | 078.10520.02F1 | C402H22 | 2355 | 2345 | 270 | NO |
| C19 | C402H22 | SC1U6D3V2KX-9-GP | 078.10520.02F1 | C402H22 | 2355 | 2305 | 270 | NO |
| C20 | C402H22 | SC1U6D3V2KX-9-GP | 078.10520.02F1 | C402H22 | 2355 | 710 | 270 | NO |
| C21 | C402H22 | SCD1U16V2KX-3GP | 78.10421.2FL | C402H22 | 2355 | 670 | 270 | NO |
| C22 | C402H22 | SCD1U16V2KX-3GP | 78.10421.2FL | C402H22 | 2355 | 750 | 270 | NO |
| C31 | C402H22 | SC1U6D3V2KX-9-GP | 078.10520.02F1 | C402H22 | 2490 | 1460 | 180 | NO |
| C32 | C402H22 | SCD1U16V2KX-3GP | 78.10421.2FL | C402H22 | 2355 | 1385 | 270 | NO |
| C33 | C402H22 | SCD1U16V2KX-3GP | 78.10421.2FL | C402H22 | 2355 | 1345 | 270 | NO |
| C34 | C402H22 | SCD1U16V2KX-3GP | 78.10421.2FL | C402H22 | 2355 | 1300 | 270 | NO |
| C35 | C805H58 | SC10U6D3V5KX-4GP | 78.10620.21L | C805H58 | 2385 | 1385 | 270 | YES |
| C36 | C805H58 | SC10U6D3V5KX-4GP | 78.10620.21L | C805H58 | 2385 | 710 | 270 | YES |
| C37 | C402H22 | SC1U6D3V2KX-9-GP | 078.10520.02F1 | C402H22 | 2355 | 1260 | 270 | NO |
| C38 | C402H22 | SC1U6D3V2KX-9-GP | 078.10520.02F1 | C402H22 | 2355 | 1220 | 270 | NO |
| C39 | C402H22 | SCD1U16V2KX-3GP | 78.10421.2FL | C402H22 | 2570 | 1645 | 270 | YES |
| C41 | C402H22 | SCD1U16V2KX-3GP | 78.10421.2FL | C402H22 | 2645 | 1550 | 0 | YES |
| C42 | C402H22 | SCD1U16V2KX-3GP | 78.10421.2FL | C402H22 | 2900 | 1615 | 0 | NO |
| C43 | C603H36 | SC1U16V3KX-5GP | 78.10521.2BL | C603H36 | 2970 | 1210 | 0 | NO |
| C267 | C402H22 | SC100P50V2JN-3GP | 78.10134.1FL | C402H22 | 2036 | 2980 | 0 | NO |
| CN1 | CH31032V2S6 | CLX-CON3-S2-GP | 21.61958.103 | CH31032V2S6 | 3020 | 3005 | 270 | NO |
| H1 | HOLE315R140 | HOLE315R140-GP | ZZ.00PAD.KZ1 | HOLE315R140 | 2874.02 | 3457.09 | 0 | NO |
| H2 | HOLE315R140 | HOLE315R140-GP | ZZ.00PAD.KZ1 | HOLE315R140 | 255.91 | 3161.81 | 0 | NO |
| H3 | HOLE315R140 | HOLE315R140-GP | ZZ.00PAD.KZ1 | HOLE315R140 | 2370.08 | 177.17 | 0 | NO |
| PC20 | C402H22 | SCD01U25V2KX-3GP | 78.10322.2FL | C402H22 | 580 | 3251.89 | 270 | NO |
| PC21 | C402H22 | SC820P50V2KX-1GP | 78.82124.2FL | C402H22 | 630 | 3016.89 | 0 | NO |
| PC22 | C402H22 | SCD01U25V2KX-3GP | 78.10322.2FL | C402H22 | 690 | 3026.89 | 270 | NO |
| PC23 | C805H56 | SC4D7U16V5KX-1-GP | 78.47521.21L | C805H56 | 805 | 2856.89 | 90 | NO |
| PC24 | C805H56 | SC22U6D3V5MX-5-GP | 78.22610.81L | C805H56 | 805 | 2936.89 | 90 | NO |
| PC25 | C805H56 | SC22U6D3V5MX-5-GP | 78.22610.81L | C805H56 | 805 | 3016.89 | 90 | NO |
| PC26 | C805H58 | SC10U6D3V5KX-4GP | 78.10620.21L | C805H58 | 620 | 3311.89 | 270 | NO |
| PC27 | C805H56 | SC22U6D3V5MX-5-GP | 78.22610.81L | C805H56 | 805 | 3311.89 | 90 | NO |
| PC28 | C402H22 | SC1KP50V2KX-1GP | 78.10224.2FL | C402H22 | 715 | 3311.89 | 180 | NO |
| PC29 | C402H22 | SC1U10V2KX-4-GP | 78.10523.8FL | C402H22 | 1650 | 3100 | 180 | NO |
| PC30 | C603 | SC2K2P50V3KX-GP | 78.22224.2BL | C603 | 1960 | 3385 | 180 | NO |
| PC31 | C603H36 | SCD1U25V3KX-GP | 78.10422.2BL | C603H36 | 1695 | 3335 | 180 | NO |
| PC32 | C805H54 | SC10U16V5KX-1-GP | 78.10621.81L | C805H54 | 1630 | 3330 | 180 | NO |
| PC33 | C805H54 | SC10U16V5KX-1-GP | 78.10621.81L | C805H54 | 1550 | 3330 | 180 | NO |
| PC34 | C805H54 | SC10U16V5KX-1-GP | 78.10621.81L | C805H54 | 1470 | 3330 | 180 | NO |
| PC35 | C805H54 | SC10U16V5KX-1-GP | 78.10621.81L | C805H54 | 1390 | 3330 | 180 | NO |
| PC36 | C805H58 | SC4D7U25V5KX-1-GP | 078.47522.0211 | C805H58 | 1558.11 | 3095 | 0 | YES |
| PC37 | C805H54 | SC10U16V5KX-1-GP | 78.10621.81L | C805H54 | 1470 | 3160 | 0 | NO |
| PC38 | C805H54 | SC10U16V5KX-1-GP | 78.10621.81L | C805H54 | 1550 | 3160 | 0 | NO |
| PC39 | C805H58 | SC10U6D3V5KX-4GP | 78.10620.21L | C805H58 | 2590 | 3040 | 90 | NO |
| PC40 | C603H36 | SCD1U50V3KX-GP | 78.10424.2BL | C603H36 | 2110 | 3200 | 90 | YES |
| PC41 | C402H22 | SCD1U25V2KX-2-GP | 78.10422.2FL | C402H22 | 2223.11 | 3060 | 0 | YES |
| PC42 | C805H58 | SC10U6D3V5KX-4GP | 78.10620.21L | C805H58 | 2590 | 2960 | 90 | NO |
| PC43 | C402H22 | SC1KP50V2KX-1GP | 78.10224.2FL | C402H22 | 2091 | 3002 | 270 | NO |
| PC45 | CT7343H83 | ST150U6D3VDM-28-GP | 077.51571.0001 | CT7343H83 | 2490 | 3275 | 180 | NO |
| PG3 | CON2C-U | COPPER-CLOSE-GP-U | ZZ.CON2C.XXX | CON2C-U | 1858.11 | 2995 | 180 | NO |
| PL2 | L20125H42 | BLM21PG220SN1DGP | 68.00084.831 | L20125H42 | 1390 | 3160 | 180 | NO |
| PL3 | L7774-1711H197 | IND-1D5UH-107-GP | 68.1R51C.10A | L7774-1711H197 | 2195 | 3240 | 90 | NO |
| PR1 | R402H16 | 37K4R2F-1-GP | 64.37425.6DL | R402H16 | 2058.11 | 3040 | 270 | NO |
| PR18 | R402H16 | 0R2J-2-GP | 63.R0034.1DL | R402H16 | 620 | 3391.89 | 0 | NO |
| PR20 | R402H16 | 10KR2F-2-GP | 64.10025.6DL | R402H16 | 725 | 3450 | 270 | NO |
| PR21 | R603H22 | 2D2R3J-2-GP | 63.2R233.15L | R603H22 | 1463.11 | 3135 | 270 | YES |
| PR22 | R402H16 | 3K65R2F-1-GP | 64.36515.6DL | R402H16 | 690 | 2986.89 | 270 | NO |
| PR23 | R402H16 | 2K87R2F-1-GP | 64.28715.6DL | R402H16 | 650 | 2941.89 | 270 | NO |
| PR24 | R603H24 | 0R3F-1-GP-U | 64.R0005.55L | R603H24 | 580 | 3176.89 | 180 | NO |
| PR25 | R402H16 | 10KR2F-2-GP | 64.10025.6DL | R402H16 | 2075 | 3095 | 90 | YES |
| PR26 | R402H16 | 2KR2F-3-GP | 64.20015.6DL | R402H16 | 2183.11 | 3060 | 0 | YES |
| PR27 | R603H22 | 10R3F-GP | 64.10R05.55L | R603H22 | 2110 | 2920 | 270 | NO |
| PR28 | R402H16 | 10KR2F-2-GP | 64.10025.6DL | R402H16 | 1998.11 | 3025 | 180 | YES |
| PR29 | R402H16 | 100KR2F-L1-GP | 64.10035.6DL | R402H16 | 1683.11 | 3000 | 0 | NO |
| PR30 | R402H16 | 100KR2F-L1-GP | 64.10035.6DL | R402H16 | 1683.11 | 3000 | 180 | YES |
| PR31 | R402H16 | 121KR2F-L-GP | 64.12135.6DL | R402H16 | 1723.11 | 3000 | 180 | YES |
| PR32 | R402H16 | 866KR2F-GP | 64.86635.6DL | R402H16 | 1763.11 | 3000 | 180 | NO |
| PR33 | R805H24 | 3D01R5F-GP | 64.3R015.16L | R805H24 | 1895 | 3400 | 0 | NO |
| PR35 | R402H16 | 619KR2F-GP | 64.61935.6DL | R402H16 | 1763.11 | 3000 | 180 | YES |
| PR36 | R402H16 | 0R2J-2-GP | 63.R0034.1DL | R402H16 | 1953.11 | 3170 | 270 | YES |
| PR37 | R402H16 | 10KR2F-2-GP | 64.10025.6DL | R402H16 | 1938.11 | 2995 | 270 | NO |
| PR38 | R603H22 | 0R3J-0-U-GP | 63.00000.00L | R603H22 | 2078.11 | 3140 | 270 | YES |
| PR39 | R402H16 | 45K3R2F-L-GP | 64.45325.6DL | R402H16 | 1998.11 | 2980 | 0 | NO |
| PU1 | QFN22G6050-G6133H60 | TPS53319DQPR-GP | 74.53319.073 | QFN22G6050-G6133H60 | 1858.11 | 3185 | 270 | NO |
| PU2 | DFN10G3-G315175H40 | TPS74801DRCR-1-GP-U | 074.74801.0033 | DFN10G3-G315175H40 | 715 | 3156.89 | 0 | NO |
| R2 | R402H16 | 0R2J-2-GP | 63.R0034.1DL | R402H16 | 2965 | 2490 | 90 | NO |
| R4 | R402H16 | 0R2J-2-GP | 63.R0034.1DL | R402H16 | 2960 | 1415 | 0 | NO |
| R5 | R402H16 | 0R2J-2-GP | 63.R0034.1DL | R402H16 | 2470 | 1525 | 90 | YES |
| R6 | R402H16 | 4K7R2F-GP | 64.47015.6DL | R402H16 | 2333.11 | 1660 | 180 | YES |
| R7 | R402H16 | 4K7R2F-GP | 64.47015.6DL | R402H16 | 2333.11 | 1585 | 0 | YES |
| R8 | R402H16 | 4K7R2F-GP | 64.47015.6DL | R402H16 | 2333.11 | 1510 | 180 | YES |
| R9 | R402H16 | 0R2J-2-GP | 63.R0034.1DL | R402H16 | 2470 | 1565 | 90 | YES |
| R10 | R402H16 | 4K7R2F-GP | 64.47015.6DL | R402H16 | 2293.11 | 1660 | 0 | YES |
| R11 | R402H16 | 4K7R2F-GP | 64.47015.6DL | R402H16 | 2293.11 | 1585 | 180 | YES |
| R12 | R402H16 | 4K7R2F-GP | 64.47015.6DL | R402H16 | 2293.11 | 1510 | 0 | YES |
| R14 | R402H16 | 0R2J-2-GP | 63.R0034.1DL | R402H16 | 2665 | 2385 | 180 | YES |
| R15 | R402H16 | 0R2J-2-GP | 63.R0034.1DL | R402H16 | 2730 | 1315 | 270 | YES |
| R21 | R402H16 | 4K7R2F-GP | 64.47015.6DL | R402H16 | 2570 | 1605 | 270 | YES |
| R23 | R402H16 | 47KR2F-GP | 64.47025.6DL | R402H16 | 2825 | 1630 | 0 | YES |
| R24 | R402H16 | 47KR2F-GP | 64.47025.6DL | R402H16 | 2645 | 1630 | 180 | YES |
| R25 | R402H16 | 4K7R2F-GP | 64.47015.6DL | R402H16 | 985 | 3210 | 270 | YES |
| R27 | R402H16 | 4K7R2F-GP | 64.47015.6DL | R402H16 | 985 | 3170 | 270 | YES |
| R28 | R402H16 | 4K7R2F-GP | 64.47015.6DL | R402H16 | 985 | 3210 | 90 | NO |
| R29 | R402H16 | 47KR2F-GP | 64.47025.6DL | R402H16 | 1100 | 2825 | 180 | YES |
| R30 | R402H16 | 47KR2F-GP | 64.47025.6DL | R402H16 | 1175 | 3395 | 180 | YES |
| R31 | R402H16 | 4K7R2F-GP | 64.47015.6DL | R402H16 | 985 | 3170 | 90 | NO |
| R32 | R402H16 | 4K7R2F-GP | 64.47015.6DL | R402H16 | 985 | 3250 | 270 | NO |
| R33 | R402H16 | 47KR2F-GP | 64.47025.6DL | R402H16 | 2565 | 2050 | 270 | YES |
| R34 | R402H16 | 47KR2F-GP | 64.47025.6DL | R402H16 | 1140 | 2825 | 180 | YES |
| R35 | R402H16 | 47KR2F-GP | 64.47025.6DL | R402H16 | 950 | 2825 | 180 | YES |
| R36 | R402H16 | 47KR2F-GP | 64.47025.6DL | R402H16 | 990 | 2825 | 180 | YES |
| R37 | R402H16 | 47KR2F-GP | 64.47025.6DL | R402H16 | 2565 | 965 | 270 | YES |
| R38 | R402H16 | 0R2J-2-GP | 63.R0034.1DL | R402H16 | 1150 | 3100 | 0 | NO |
| R39 | R402H16 | 0R2J-2-GP | 63.R0034.1DL | R402H16 | 1190 | 3100 | 0 | NO |
| R40 | R402H16 | 0R2J-2-GP | 63.R0034.1DL | R402H16 | 1275 | 3100 | 0 | NO |
| R41 | R402H16 | 0R2J-2-GP | 63.R0034.1DL | R402H16 | 1235 | 3100 | 0 | NO |
| R42 | R402H16 | 4K7R2F-GP | 64.47015.6DL | R402H16 | 2565 | 885 | 90 | YES |
| R43 | R402H16 | 4K7R2F-GP | 64.47015.6DL | R402H16 | 2565 | 1970 | 90 | YES |
| R44 | R402H16 | 47KR2F-GP | 64.47025.6DL | R402H16 | 2940 | 1525 | 180 | NO |
| R45 | R402H16 | 47KR2F-GP | 64.47025.6DL | R402H16 | 2980 | 1525 | 180 | NO |
| R46 | R402H16 | 47KR2F-GP | 64.47025.6DL | R402H16 | 2965 | 2450 | 270 | NO |
| R47 | R402H16 | 47KR2F-GP | 64.47025.6DL | R402H16 | 2960 | 1340 | 0 | NO |
| R48 | R402H16 | 47KR2F-GP | 64.47025.6DL | R402H16 | 2730 | 1355 | 270 | YES |
| R49 | R402H16 | 47KR2F-GP | 64.47025.6DL | R402H16 | 2705 | 2385 | 180 | YES |
| R50 | R402H16 | 47KR2F-GP | 64.47025.6DL | R402H16 | 1135 | 3395 | 0 | YES |
| R51 | R402H16 | 47KR2F-GP | 64.47025.6DL | R402H16 | 1090 | 3395 | 0 | YES |
| R52 | R402H16 | 33R2J-2-GP | 63.33034.1DL | R402H16 | 1190 | 2820 | 0 | NO |
| R53 | R402H16 | 33R2J-2-GP | 63.33034.1DL | R402H16 | 1145 | 2835 | 0 | NO |
| R54 | R402H16 | 10KR2F-2-GP | 64.10025.6DL | R402H16 | 1215 | 2930 | 90 | YES |
| R55 | R402H16 | 33R2J-2-GP | 63.33034.1DL | R402H16 | 990 | 2825 | 0 | NO |
| R56 | R402H16 | 33R2J-2-GP | 63.33034.1DL | R402H16 | 950 | 2825 | 0 | NO |
| R57 | R402H16 | 10KR2F-2-GP | 64.10025.6DL | R402H16 | 1000 | 2940 | 0 | YES |
| R58 | R402H16 | 47KR2F-GP | 64.47025.6DL | R402H16 | 1150 | 3100 | 0 | YES |
| R59 | R402H16 | 47KR2F-GP | 64.47025.6DL | R402H16 | 1215 | 3395 | 180 | YES |
| R60 | R402H16 | 47KR2F-GP | 64.47025.6DL | R402H16 | 1190 | 3100 | 0 | YES |
| R61 | R402H16 | 0R2J-2-GP | 63.R0034.1DL | R402H16 | 925 | 3040 | 0 | YES |
| R62 | R402H16 | 0R2J-2-GP | 63.R0034.1DL | R402H16 | 1045 | 3040 | 0 | YES |
| R63 | R402H16 | 0R2J-2-GP | 63.R0034.1DL | R402H16 | 965 | 3040 | 0 | YES |
| R64 | R402H16 | 0R2J-2-GP | 63.R0034.1DL | R402H16 | 1005 | 3040 | 0 | YES |
| SKT1 | 78758-0001 | SKT-SAS28-P15-PCIE25-2-GP | 20.F2475.068 | 78758-0001 | 3116.14 | 1086.42 | 90 | YES |
| SSD_A1 | MDT580M01001 | SKT-MINI75P-11-GP | 020.C0085.0075 | MDT580M01001 | 2655.51 | 2127.56 | 270 | NO |
| SSD_B1 | MDT580M01001 | SKT-MINI75P-11-GP | 020.C0085.0075 | MDT580M01001 | 2655.51 | 1040.94 | 270 | NO |
| TP1 | TPAD28-1-U | TPAD28-1-GP-U | ZZ.00PAD.1F1 | TPAD28-1-U | 2580 | 1605 | 180 | NO |
| TP2 | TPAD28-1-U | TPAD28-1-GP-U | ZZ.00PAD.1F1 | TPAD28-1-U | 1623.11 | 2985 | 0 | NO |
| TP5 | TPAD28-1-U | TPAD28-1-GP-U | ZZ.00PAD.1F1 | TPAD28-1-U | 680 | 3391.89 | 0 | NO |
| TP6 | TPAD28-1-U | TPAD28-1-GP-U | ZZ.00PAD.1F1 | TPAD28-1-U | 2520 | 1910 | 0 | YES |
| TP7 | TPAD28-1-U | TPAD28-1-GP-U | ZZ.00PAD.1F1 | TPAD28-1-U | 2595 | 1910 | 0 | YES |
| TP8 | TPAD28-1-U | TPAD28-1-GP-U | ZZ.00PAD.1F1 | TPAD28-1-U | 2520 | 823.38 | 0 | YES |
| TP9 | TPAD28-1-U | TPAD28-1-GP-U | ZZ.00PAD.1F1 | TPAD28-1-U | 2595 | 823.38 | 0 | YES |
| U1 | MSOP8-1H44 | TMP75AIDGKR-GP | 74.00075.B79 | MSOP8-1H44 | 2385 | 1585 | 90 | NO |
| U3 | SC70-5H44 | 74LVC1G32DC-1GP | 73.01G32.A0H | SC70-5H44 | 2735 | 1590 | 0 | YES |
| U4 | TSOIC14H44 | PCA9543APW-GP | 71.09543.00W | TSOIC14H44 | 1150 | 3311.89 | 0 | NO |
| U5 | SC70-5H44 | 74LVC1G32DC-1GP | 73.01G32.A0H | SC70-5H44 | 2980 | 1655 | 180 | NO |
| U6 | SSOIC8-4H36 | TXS0102DCUR-1-GP | 73.00102.007 | SSOIC8-4H36 | 1185 | 2950 | 270 | NO |
| U7 | SSOIC8-4H36 | TXS0102DCUR-1-GP | 73.00102.007 | SSOIC8-4H36 | 1020 | 2985 | 180 | NO |
